(kicad_pcb
	(version 20260206)
	(generator "pcbnew")
	(generator_version "10.0")
	(general
		(thickness 1.6)
		(legacy_teardrops no)
	)
	(paper "A4")
	(title_block
		(title "Wiwynn_Tioga_Pass_MB.brd")
		(comment 1 "Tioga Pass / footprint 2254 of 4770 (U5D1), pads 2074-2187 of 3647")
	)
	(layers
		(0 "F.Cu" signal "TOP")
		(4 "In1.Cu" signal "L2GND")
		(6 "In2.Cu" signal "L3")
		(8 "In3.Cu" signal "L4GND")
		(10 "In4.Cu" signal "L5")
		(12 "In5.Cu" signal "L6GND")
		(14 "In6.Cu" signal "L7VCC")
		(16 "In7.Cu" signal "L8VCC")
		(18 "In8.Cu" signal "L9GND")
		(20 "In9.Cu" signal "L10")
		(22 "In10.Cu" signal "L11GND")
		(24 "In11.Cu" signal "L12")
		(26 "In12.Cu" signal "L13GND")
		(2 "B.Cu" signal "BOTTOM")
		(9 "F.Adhes" user "F.Adhesive")
		(11 "B.Adhes" user "B.Adhesive")
		(13 "F.Paste" user "Package Geometry/Pastemask Top")
		(15 "B.Paste" user "Package Geometry/Pastemask Bottom")
		(5 "F.SilkS" user "Ref Des/Silkscreen Top")
		(7 "B.SilkS" user "Ref Des/Silkscreen Bottom")
		(1 "F.Mask" user "Board Geometry/Soldermask Top")
		(3 "B.Mask" user "Board Geometry/Soldermask Bottom")
		(17 "Dwgs.User" user "User.Drawings")
		(19 "Cmts.User" user "User.Comments")
		(21 "Eco1.User" user "User.Eco1")
		(23 "Eco2.User" user "User.Eco2")
		(25 "Edge.Cuts" user "Board Geometry/Outline")
		(27 "Margin" user)
		(31 "F.CrtYd" user "Package Geometry/Place Bound Top")
		(29 "B.CrtYd" user "Package Geometry/Place Bound Bottom")
		(35 "F.Fab" user "Ref Des/Assembly Top")
		(33 "B.Fab" user "Ref Des/Assembly Bottom")
	)
	(footprint ""
		(layer "F.Cu")
		(at 270.000222 -76.550012 180)
		(property "Reference" "U5D1"
			(at 19.124422 31.601918 0)
			(unlocked yes)
			(layer "F.SilkS")
			(effects
				(font
					(size 0.7874 0.5842)
					(thickness 0.1524)
				)
			)
		)
		(property "Value" ""
			(at 0 0 180)
			(layer "F.Fab")
			(effects
				(font
					(size 1.27 1.27)
				)
			)
		)
		(duplicate_pad_numbers_are_jumpers no)
		(pad "DD13" smd circle
			(at -26.948384 16.006572)
			(size 0.4318 0.4318)
			(layers "F.Cu" "F.Mask" "F.Paste")
			(net "P3E_CPU0_PE3_OCP_RXN<12>")
		)
		(pad "DD15" smd circle
			(at -25.231598 16.006572)
			(size 0.4318 0.4318)
			(layers "F.Cu" "F.Mask" "F.Paste")
			(net "TP_CPU0_UPI2_RSVD_CV13")
		)
		(pad "DD17" smd circle
			(at -23.514558 16.006572)
			(size 0.4318 0.4318)
			(layers "F.Cu" "F.Mask" "F.Paste")
			(net "TP_CPU0_UPI2_RSVD_CU14")
		)
		(pad "DD19" smd circle
			(at -21.797518 16.006572)
			(size 0.4318 0.4318)
			(layers "F.Cu" "F.Mask" "F.Paste")
			(net "GND")
		)
		(pad "DD21" smd circle
			(at -20.080478 16.006572)
			(size 0.4318 0.4318)
			(layers "F.Cu" "F.Mask" "F.Paste")
			(net "GND")
		)
		(pad "DD23" smd circle
			(at -18.363438 16.006572)
			(size 0.4318 0.4318)
			(layers "F.Cu" "F.Mask" "F.Paste")
			(net "GND")
		)
		(pad "DD25" smd circle
			(at -16.646398 16.006572)
			(size 0.4318 0.4318)
			(layers "F.Cu" "F.Mask" "F.Paste")
			(net "M_E_DQ<58>")
		)
		(pad "DD27" smd circle
			(at -14.929612 16.006572)
			(size 0.4318 0.4318)
			(layers "F.Cu" "F.Mask" "F.Paste")
			(net "GND")
		)
		(pad "DD29" smd circle
			(at -13.212572 16.006572)
			(size 0.4318 0.4318)
			(layers "F.Cu" "F.Mask" "F.Paste")
			(net "M_F_DQS_DN<7>")
		)
		(pad "DD31" smd circle
			(at -11.495532 16.006572)
			(size 0.4318 0.4318)
			(layers "F.Cu" "F.Mask" "F.Paste")
			(net "GND")
		)
		(pad "DD33" smd circle
			(at -9.778492 16.006572)
			(size 0.4318 0.4318)
			(layers "F.Cu" "F.Mask" "F.Paste")
			(net "GND")
		)
		(pad "DD35" smd circle
			(at -8.061452 16.006572)
			(size 0.4318 0.4318)
			(layers "F.Cu" "F.Mask" "F.Paste")
			(net "M_F_DQS_DN<6>")
		)
		(pad "DD37" smd circle
			(at -6.344412 16.006572)
			(size 0.4318 0.4318)
			(layers "F.Cu" "F.Mask" "F.Paste")
			(net "GND")
		)
		(pad "DD39" smd circle
			(at -4.627626 16.006572)
			(size 0.4318 0.4318)
			(layers "F.Cu" "F.Mask" "F.Paste")
			(net "M_F_DQ<38>")
		)
		(pad "DD41" smd circle
			(at -2.910586 16.006572)
			(size 0.4318 0.4318)
			(layers "F.Cu" "F.Mask" "F.Paste")
			(net "M_F_DQ<32>")
		)
		(pad "DD45" smd circle
			(at 2.052066 14.206474)
			(size 0.4318 0.4318)
			(layers "F.Cu" "F.Mask" "F.Paste")
			(net "PVDDQ_DEF")
		)
		(pad "DD47" smd circle
			(at 3.769106 14.206474)
			(size 0.4318 0.4318)
			(layers "F.Cu" "F.Mask" "F.Paste")
			(net "A_CPU0_DEF_RCOMP1")
		)
		(pad "DD49" smd circle
			(at 5.485892 14.206474)
			(size 0.4318 0.4318)
			(layers "F.Cu" "F.Mask" "F.Paste")
			(net "A_CPU0_DEF_RCOMP2")
		)
		(pad "DD51" smd circle
			(at 7.202932 14.206474)
			(size 0.4318 0.4318)
			(layers "F.Cu" "F.Mask" "F.Paste")
			(net "TP_CPU0_RSVD_45")
		)
		(pad "DD53" smd circle
			(at 8.919972 14.206474)
			(size 0.4318 0.4318)
			(layers "F.Cu" "F.Mask" "F.Paste")
			(net "M_F_MA<13>")
		)
		(pad "DD55" smd circle
			(at 10.637012 14.206474)
			(size 0.4318 0.4318)
			(layers "F.Cu" "F.Mask" "F.Paste")
			(net "M_F_MA<10>")
		)
		(pad "DD57" smd circle
			(at 12.354052 14.206474)
			(size 0.4318 0.4318)
			(layers "F.Cu" "F.Mask" "F.Paste")
			(net "M_F_MA<2>")
		)
		(pad "DD59" smd circle
			(at 14.071092 14.206474)
			(size 0.4318 0.4318)
			(layers "F.Cu" "F.Mask" "F.Paste")
			(net "M_F_MA<8>")
		)
		(pad "DD61" smd circle
			(at 15.787878 14.206474)
			(size 0.4318 0.4318)
			(layers "F.Cu" "F.Mask" "F.Paste")
			(net "M_F_ALERT_N")
		)
		(pad "DD63" smd circle
			(at 17.504918 14.206474)
			(size 0.4318 0.4318)
			(layers "F.Cu" "F.Mask" "F.Paste")
			(net "M_F_CKE<1>")
		)
		(pad "DD65" smd circle
			(at 19.221958 14.206474)
			(size 0.4318 0.4318)
			(layers "F.Cu" "F.Mask" "F.Paste")
			(net "M_D_ECC<3>")
		)
		(pad "DD67" smd circle
			(at 20.938998 14.206474)
			(size 0.4318 0.4318)
			(layers "F.Cu" "F.Mask" "F.Paste")
			(net "M_D_DQS_DP<8>")
		)
		(pad "DD69" smd circle
			(at 22.656038 14.206474)
			(size 0.4318 0.4318)
			(layers "F.Cu" "F.Mask" "F.Paste")
			(net "M_D_ECC<5>")
		)
		(pad "DD71" smd circle
			(at 24.373078 14.206474)
			(size 0.4318 0.4318)
			(layers "F.Cu" "F.Mask" "F.Paste")
			(net "GND")
		)
		(pad "DD73" smd circle
			(at 26.090118 14.206474)
			(size 0.4318 0.4318)
			(layers "F.Cu" "F.Mask" "F.Paste")
			(net "GND")
		)
		(pad "DD75" smd circle
			(at 27.806904 14.206474)
			(size 0.4318 0.4318)
			(layers "F.Cu" "F.Mask" "F.Paste")
			(net "GND")
		)
		(pad "DD77" smd circle
			(at 29.523944 14.206474)
			(size 0.4318 0.4318)
			(layers "F.Cu" "F.Mask" "F.Paste")
			(net "M_F_DQS_DN<1>")
		)
		(pad "DD79" smd circle
			(at 31.240984 14.206474)
			(size 0.4318 0.4318)
			(layers "F.Cu" "F.Mask" "F.Paste")
			(net "M_E_DQS_DP<10>")
		)
		(pad "DD81" smd circle
			(at 32.958024 14.206474)
			(size 0.4318 0.4318)
			(layers "F.Cu" "F.Mask" "F.Paste")
			(net "GND")
		)
		(pad "DD83" smd circle
			(at 34.675064 14.206474)
			(size 0.4318 0.4318)
			(layers "F.Cu" "F.Mask" "F.Paste")
			(net "GND")
		)
		(pad "DD85" smd custom
			(at 36.392104 14.206474 270)
			(size 0.10795 0.10795)
			(layers "F.Cu" "F.Mask" "F.Paste")
			(net "M_D_DQ<12>")
			(options
				(clearance outline)
				(anchor circle)
			)
			(primitives
				(gr_poly
					(pts
						(arc
							(start 0.2159 -0.0381)
							(mid 0 -0.254)
							(end -0.2159 -0.0381)
						)
						(arc
							(start -0.2159 0.0381)
							(mid 0 0.254)
							(end 0.2159 0.0381)
						)
					)
					(width 0)
					(fill yes)
				)
			)
		)
		(pad "DE2" smd custom
			(at -36.392104 16.502126 90)
			(size 0.10795 0.10795)
			(layers "F.Cu" "F.Mask" "F.Paste")
			(net "P3E_CPU0_PE1_SS_TXN<2>")
			(options
				(clearance outline)
				(anchor circle)
			)
			(primitives
				(gr_poly
					(pts
						(arc
							(start 0.2159 -0.0381)
							(mid 0 -0.254)
							(end -0.2159 -0.0381)
						)
						(arc
							(start -0.2159 0.0381)
							(mid 0 0.254)
							(end 0.2159 0.0381)
						)
					)
					(width 0)
					(fill yes)
				)
			)
		)
		(pad "DE4" smd circle
			(at -34.675064 16.502126)
			(size 0.4318 0.4318)
			(layers "F.Cu" "F.Mask" "F.Paste")
			(net "P3E_CPU0_PE1_SS_TXN<3>")
		)
		(pad "DE6" smd circle
			(at -32.958024 16.502126)
			(size 0.4318 0.4318)
			(layers "F.Cu" "F.Mask" "F.Paste")
			(net "GND")
		)
		(pad "DE8" smd circle
			(at -31.240984 16.502126)
			(size 0.4318 0.4318)
			(layers "F.Cu" "F.Mask" "F.Paste")
			(net "GND")
		)
		(pad "DE10" smd circle
			(at -29.523944 16.502126)
			(size 0.4318 0.4318)
			(layers "F.Cu" "F.Mask" "F.Paste")
			(net "P3E_CPU0_PE1_SS_RXN<4>")
		)
		(pad "DE12" smd circle
			(at -27.806904 16.502126)
			(size 0.4318 0.4318)
			(layers "F.Cu" "F.Mask" "F.Paste")
			(net "P3E_CPU0_PE3_OCP_RXP<10>")
		)
		(pad "DE14" smd circle
			(at -26.090118 16.502126)
			(size 0.4318 0.4318)
			(layers "F.Cu" "F.Mask" "F.Paste")
			(net "PVCCIO_CPU0")
		)
		(pad "DE16" smd circle
			(at -24.373078 16.502126)
			(size 0.4318 0.4318)
			(layers "F.Cu" "F.Mask" "F.Paste")
			(net "TP_CPU0_UPI2_RSVD_CR14")
		)
		(pad "DE18" smd circle
			(at -22.656038 16.502126)
			(size 0.4318 0.4318)
			(layers "F.Cu" "F.Mask" "F.Paste")
			(net "GND")
		)
		(pad "DE20" smd circle
			(at -20.938998 16.502126)
			(size 0.4318 0.4318)
			(layers "F.Cu" "F.Mask" "F.Paste")
			(net "GND")
		)
		(pad "DE22" smd circle
			(at -19.221958 16.502126)
			(size 0.4318 0.4318)
			(layers "F.Cu" "F.Mask" "F.Paste")
			(net "GND")
		)
		(pad "DE24" smd circle
			(at -17.504918 16.502126)
			(size 0.4318 0.4318)
			(layers "F.Cu" "F.Mask" "F.Paste")
			(net "GND")
		)
		(pad "DE26" smd circle
			(at -15.787878 16.502126)
			(size 0.4318 0.4318)
			(layers "F.Cu" "F.Mask" "F.Paste")
			(net "M_E_DQS_DP<16>")
		)
		(pad "DE28" smd circle
			(at -14.071092 16.502126)
			(size 0.4318 0.4318)
			(layers "F.Cu" "F.Mask" "F.Paste")
			(net "GND")
		)
		(pad "DE30" smd circle
			(at -12.354052 16.502126)
			(size 0.4318 0.4318)
			(layers "F.Cu" "F.Mask" "F.Paste")
			(net "GND")
		)
		(pad "DE32" smd circle
			(at -10.637012 16.502126)
			(size 0.4318 0.4318)
			(layers "F.Cu" "F.Mask" "F.Paste")
			(net "M_F_DQS_DP<14>")
		)
		(pad "DE34" smd circle
			(at -8.919972 16.502126)
			(size 0.4318 0.4318)
			(layers "F.Cu" "F.Mask" "F.Paste")
			(net "GND")
		)
		(pad "DE36" smd circle
			(at -7.202932 16.502126)
			(size 0.4318 0.4318)
			(layers "F.Cu" "F.Mask" "F.Paste")
			(net "GND")
		)
		(pad "DE38" smd circle
			(at -5.485892 16.502126)
			(size 0.4318 0.4318)
			(layers "F.Cu" "F.Mask" "F.Paste")
			(net "M_F_DQ<34>")
		)
		(pad "DE40" smd circle
			(at -3.769106 16.502126)
			(size 0.4318 0.4318)
			(layers "F.Cu" "F.Mask" "F.Paste")
			(net "M_F_DQS_DN<13>")
		)
		(pad "DE42" smd circle
			(at -2.052066 16.502126)
			(size 0.4318 0.4318)
			(layers "F.Cu" "F.Mask" "F.Paste")
			(net "M_F_DQ<37>")
		)
		(pad "DE44" smd circle
			(at 1.193546 14.702028)
			(size 0.508 0.508)
			(layers "F.Cu" "F.Mask" "F.Paste")
			(net "SVID_ALERT0_CPU0_N")
		)
		(pad "DE46" smd circle
			(at 2.910586 14.702028)
			(size 0.4318 0.4318)
			(layers "F.Cu" "F.Mask" "F.Paste")
			(net "M_F_MA<17>")
		)
		(pad "DE48" smd circle
			(at 4.627626 14.702028)
			(size 0.4318 0.4318)
			(layers "F.Cu" "F.Mask" "F.Paste")
			(net "GND")
		)
		(pad "DE50" smd circle
			(at 6.344412 14.702028)
			(size 0.4318 0.4318)
			(layers "F.Cu" "F.Mask" "F.Paste")
			(net "GND")
		)
		(pad "DE52" smd circle
			(at 8.061452 14.702028)
			(size 0.4318 0.4318)
			(layers "F.Cu" "F.Mask" "F.Paste")
			(net "GND")
		)
		(pad "DE54" smd circle
			(at 9.778492 14.702028)
			(size 0.4318 0.4318)
			(layers "F.Cu" "F.Mask" "F.Paste")
			(net "GND")
		)
		(pad "DE56" smd circle
			(at 11.495532 14.702028)
			(size 0.4318 0.4318)
			(layers "F.Cu" "F.Mask" "F.Paste")
			(net "GND")
		)
		(pad "DE58" smd circle
			(at 13.212572 14.702028)
			(size 0.4318 0.4318)
			(layers "F.Cu" "F.Mask" "F.Paste")
			(net "GND")
		)
		(pad "DE60" smd circle
			(at 14.929612 14.702028)
			(size 0.4318 0.4318)
			(layers "F.Cu" "F.Mask" "F.Paste")
			(net "GND")
		)
		(pad "DE62" smd circle
			(at 16.646398 14.702028)
			(size 0.4318 0.4318)
			(layers "F.Cu" "F.Mask" "F.Paste")
			(net "GND")
		)
		(pad "DE64" smd circle
			(at 18.363438 14.702028)
			(size 0.4318 0.4318)
			(layers "F.Cu" "F.Mask" "F.Paste")
			(net "GND")
		)
		(pad "DE66" smd circle
			(at 20.080478 14.702028)
			(size 0.4318 0.4318)
			(layers "F.Cu" "F.Mask" "F.Paste")
			(net "M_D_ECC<7>")
		)
		(pad "DE68" smd circle
			(at 21.797518 14.702028)
			(size 0.4318 0.4318)
			(layers "F.Cu" "F.Mask" "F.Paste")
			(net "M_D_ECC<1>")
		)
		(pad "DE70" smd circle
			(at 23.514558 14.702028)
			(size 0.4318 0.4318)
			(layers "F.Cu" "F.Mask" "F.Paste")
			(net "GND")
		)
		(pad "DE72" smd circle
			(at 25.231598 14.702028)
			(size 0.4318 0.4318)
			(layers "F.Cu" "F.Mask" "F.Paste")
			(net "GND")
		)
		(pad "DE74" smd circle
			(at 26.948384 14.702028)
			(size 0.4318 0.4318)
			(layers "F.Cu" "F.Mask" "F.Paste")
			(net "M_F_DQ<8>")
		)
		(pad "DE76" smd circle
			(at 28.665424 14.702028)
			(size 0.4318 0.4318)
			(layers "F.Cu" "F.Mask" "F.Paste")
			(net "M_F_DQS_DP<1>")
		)
		(pad "DE78" smd circle
			(at 30.382464 14.702028)
			(size 0.4318 0.4318)
			(layers "F.Cu" "F.Mask" "F.Paste")
			(net "GND")
		)
		(pad "DE80" smd circle
			(at 32.099504 14.702028)
			(size 0.4318 0.4318)
			(layers "F.Cu" "F.Mask" "F.Paste")
			(net "M_E_DQ<10>")
		)
		(pad "DE82" smd circle
			(at 33.816544 14.702028)
			(size 0.4318 0.4318)
			(layers "F.Cu" "F.Mask" "F.Paste")
			(net "M_E_DQ<15>")
		)
		(pad "DE84" smd circle
			(at 35.533584 14.702028)
			(size 0.4318 0.4318)
			(layers "F.Cu" "F.Mask" "F.Paste")
			(net "M_D_DQ<13>")
		)
		(pad "DF3" smd circle
			(at -35.533584 16.997172)
			(size 0.4318 0.4318)
			(layers "F.Cu" "F.Mask" "F.Paste")
			(net "P3E_CPU0_PE1_SS_TXP<4>")
		)
		(pad "DF5" smd circle
			(at -33.816544 16.997172)
			(size 0.4318 0.4318)
			(layers "F.Cu" "F.Mask" "F.Paste")
			(net "GND")
		)
		(pad "DF7" smd circle
			(at -32.099504 16.997172)
			(size 0.4318 0.4318)
			(layers "F.Cu" "F.Mask" "F.Paste")
			(net "GND")
		)
		(pad "DF9" smd circle
			(at -30.382464 16.997172)
			(size 0.4318 0.4318)
			(layers "F.Cu" "F.Mask" "F.Paste")
			(net "P3E_CPU0_PE1_SS_RXP<5>")
		)
		(pad "DF11" smd circle
			(at -28.665424 16.997172)
			(size 0.4318 0.4318)
			(layers "F.Cu" "F.Mask" "F.Paste")
			(net "P3E_CPU0_PE3_OCP_RXP<11>")
		)
		(pad "DF13" smd circle
			(at -26.948384 16.997172)
			(size 0.4318 0.4318)
			(layers "F.Cu" "F.Mask" "F.Paste")
			(net "PVCCIO_CPU0")
		)
		(pad "DF15" smd circle
			(at -25.231598 16.997172)
			(size 0.4318 0.4318)
			(layers "F.Cu" "F.Mask" "F.Paste")
			(net "TP_CPU0_UPI2_RSVD_CW14")
		)
		(pad "DF17" smd circle
			(at -23.514558 16.997172)
			(size 0.4318 0.4318)
			(layers "F.Cu" "F.Mask" "F.Paste")
			(net "TP_CPU0_UPI2_RSVD_CK13")
		)
		(pad "DF19" smd circle
			(at -21.797518 16.997172)
			(size 0.4318 0.4318)
			(layers "F.Cu" "F.Mask" "F.Paste")
			(net "GND")
		)
		(pad "DF21" smd circle
			(at -20.080478 16.997172)
			(size 0.4318 0.4318)
			(layers "F.Cu" "F.Mask" "F.Paste")
			(net "PVCCIO_CPU0")
		)
		(pad "DF23" smd circle
			(at -18.363438 16.997172)
			(size 0.4318 0.4318)
			(layers "F.Cu" "F.Mask" "F.Paste")
			(net "GND")
		)
		(pad "DF25" smd circle
			(at -16.646398 16.997172)
			(size 0.4318 0.4318)
			(layers "F.Cu" "F.Mask" "F.Paste")
			(net "M_E_DQ<62>")
		)
		(pad "DF27" smd circle
			(at -14.929612 16.997172)
			(size 0.4318 0.4318)
			(layers "F.Cu" "F.Mask" "F.Paste")
			(net "M_E_DQ<56>")
		)
		(pad "DF29" smd circle
			(at -13.212572 16.997172)
			(size 0.4318 0.4318)
			(layers "F.Cu" "F.Mask" "F.Paste")
			(net "GND")
		)
		(pad "DF31" smd circle
			(at -11.495532 16.997172)
			(size 0.4318 0.4318)
			(layers "F.Cu" "F.Mask" "F.Paste")
			(net "M_F_DQ<46>")
		)
		(pad "DF33" smd circle
			(at -9.778492 16.997172)
			(size 0.4318 0.4318)
			(layers "F.Cu" "F.Mask" "F.Paste")
			(net "M_F_DQ<40>")
		)
		(pad "DF35" smd circle
			(at -8.061452 16.997172)
			(size 0.4318 0.4318)
			(layers "F.Cu" "F.Mask" "F.Paste")
			(net "GND")
		)
		(pad "DF37" smd circle
			(at -6.344412 16.997172)
			(size 0.4318 0.4318)
			(layers "F.Cu" "F.Mask" "F.Paste")
			(net "GND")
		)
		(pad "DF39" smd circle
			(at -4.627626 16.997172)
			(size 0.4318 0.4318)
			(layers "F.Cu" "F.Mask" "F.Paste")
			(net "GND")
		)
		(pad "DF41" smd circle
			(at -2.910586 16.997172)
			(size 0.4318 0.4318)
			(layers "F.Cu" "F.Mask" "F.Paste")
			(net "GND")
		)
		(pad "DF45" smd circle
			(at 2.052066 15.197074)
			(size 0.4318 0.4318)
			(layers "F.Cu" "F.Mask" "F.Paste")
			(net "M_F_C<2>")
		)
		(pad "DF47" smd circle
			(at 3.769106 15.197074)
			(size 0.4318 0.4318)
			(layers "F.Cu" "F.Mask" "F.Paste")
			(net "M_F_ODT<3>")
		)
		(pad "DF49" smd circle
			(at 5.485892 15.197074)
			(size 0.4318 0.4318)
			(layers "F.Cu" "F.Mask" "F.Paste")
			(net "M_F_CS_N<1>")
		)
		(pad "DF51" smd circle
			(at 7.202932 15.197074)
			(size 0.4318 0.4318)
			(layers "F.Cu" "F.Mask" "F.Paste")
			(net "M_F_CS_N<4>")
		)
		(pad "DF53" smd circle
			(at 8.919972 15.197074)
			(size 0.4318 0.4318)
			(layers "F.Cu" "F.Mask" "F.Paste")
			(net "M_F_MA<0>")
		)
		(pad "DF55" smd circle
			(at 10.637012 15.197074)
			(size 0.4318 0.4318)
			(layers "F.Cu" "F.Mask" "F.Paste")
			(net "M_F_CLK_DN<1>")
		)
		(pad "DF57" smd circle
			(at 12.354052 15.197074)
			(size 0.4318 0.4318)
			(layers "F.Cu" "F.Mask" "F.Paste")
			(net "M_F_CLK_DN<3>")
		)
		(pad "DF59" smd circle
			(at 14.071092 15.197074)
			(size 0.4318 0.4318)
			(layers "F.Cu" "F.Mask" "F.Paste")
			(net "M_F_MA<5>")
		)
		(pad "DF61" smd circle
			(at 15.787878 15.197074)
			(size 0.4318 0.4318)
			(layers "F.Cu" "F.Mask" "F.Paste")
			(net "M_F_BG<1>")
		)
		(pad "DF63" smd circle
			(at 17.504918 15.197074)
			(size 0.4318 0.4318)
			(layers "F.Cu" "F.Mask" "F.Paste")
			(net "M_F_CKE<3>")
		)
		(pad "DF65" smd circle
			(at 19.221958 15.197074)
			(size 0.4318 0.4318)
			(layers "F.Cu" "F.Mask" "F.Paste")
			(net "GND")
		)
		(pad "DF67" smd circle
			(at 20.938998 15.197074)
			(size 0.4318 0.4318)
			(layers "F.Cu" "F.Mask" "F.Paste")
			(net "M_D_DQS_DN<8>")
		)
		(pad "DF69" smd circle
			(at 22.656038 15.197074)
			(size 0.4318 0.4318)
			(layers "F.Cu" "F.Mask" "F.Paste")
			(net "GND")
		)
		(pad "DF71" smd circle
			(at 24.373078 15.197074)
			(size 0.4318 0.4318)
			(layers "F.Cu" "F.Mask" "F.Paste")
			(net "M_F_DQ<20>")
		)
		(pad "DF73" smd circle
			(at 26.090118 15.197074)
			(size 0.4318 0.4318)
			(layers "F.Cu" "F.Mask" "F.Paste")
			(net "GND")
		)
		(pad "DF75" smd circle
			(at 27.806904 15.197074)
			(size 0.4318 0.4318)
			(layers "F.Cu" "F.Mask" "F.Paste")
			(net "M_F_DQS_DN<10>")
		)
	)
)
